(kicad_pcb
	(version 20260206)
	(generator "pcbnew")
	(generator_version "10.0")
	(general
		(thickness 1.6)
		(legacy_teardrops no)
	)
	(paper "A4")
	(title_block
		(title "04192023_DAF0TMB3IC0_F0TG_MB_C_brd_V02_OCP.brd")
		(comment 1 "Grand Teton / footprint 2449 of 8354 (J23), pads 114-226 of 291")
	)
	(layers
		(0 "F.Cu" signal "TOP")
		(4 "In1.Cu" signal "GND")
		(6 "In2.Cu" signal "IN1")
		(8 "In3.Cu" signal "GND1")
		(10 "In4.Cu" signal "IN2")
		(12 "In5.Cu" signal "GND2")
		(14 "In6.Cu" signal "IN3")
		(16 "In7.Cu" signal "GND3")
		(18 "In8.Cu" signal "VCC")
		(20 "In9.Cu" signal "VCC1")
		(22 "In10.Cu" signal "GND4")
		(24 "In11.Cu" signal "IN4")
		(26 "In12.Cu" signal "GND5")
		(28 "In13.Cu" signal "IN5")
		(30 "In14.Cu" signal "GND6")
		(32 "In15.Cu" signal "IN6")
		(34 "In16.Cu" signal "GND7")
		(2 "B.Cu" signal "BOTTOM")
		(9 "F.Adhes" user "F.Adhesive")
		(11 "B.Adhes" user "B.Adhesive")
		(13 "F.Paste" user "Package Geometry/Pastemask Top")
		(15 "B.Paste" user "Package Geometry/Pastemask Bottom")
		(5 "F.SilkS" user "Ref Des/Silkscreen Top")
		(7 "B.SilkS" user "Ref Des/Silkscreen Bottom")
		(1 "F.Mask" user "Board Geometry/Soldermask Top")
		(3 "B.Mask" user "Board Geometry/Soldermask Bottom")
		(17 "Dwgs.User" user "User.Drawings")
		(19 "Cmts.User" user "User.Comments")
		(21 "Eco1.User" user "User.Eco1")
		(23 "Eco2.User" user "User.Eco2")
		(25 "Edge.Cuts" user "Board Geometry/Outline")
		(27 "Margin" user)
		(31 "F.CrtYd" user "Package Geometry/Place Bound Top")
		(29 "B.CrtYd" user "Package Geometry/Place Bound Bottom")
		(35 "F.Fab" user "Ref Des/Assembly Top")
		(33 "B.Fab" user "Ref Des/Assembly Bottom")
	)
	(footprint ""
		(layer "F.Cu")
		(at 267.598144 -255.560068 180)
		(property "Reference" "J23"
			(at -2.2098 -81.984088 0)
			(unlocked yes)
			(layer "F.SilkS")
			(effects
				(font
					(size 0.7874 0.5842)
					(thickness 0.1524)
				)
			)
		)
		(property "Value" ""
			(at 0 0 180)
			(layer "F.Fab")
			(effects
				(font
					(size 1.27 1.27)
				)
			)
		)
		(duplicate_pad_numbers_are_jumpers no)
		(pad "114" smd rect
			(at -2.050034 37.824918 90)
			(size 0.519938 1.4986)
			(layers "F.Cu" "F.Mask" "F.Paste")
			(net "GND")
		)
		(pad "115" smd rect
			(at -2.050034 38.675056 90)
			(size 0.519938 1.4986)
			(layers "F.Cu" "F.Mask" "F.Paste")
			(net "M_F_CPU0_SB_DQS_DP<1>")
		)
		(pad "116" smd rect
			(at -2.050034 39.52494 90)
			(size 0.519938 1.4986)
			(layers "F.Cu" "F.Mask" "F.Paste")
			(net "M_F_CPU0_SB_DQS_DN<1>")
		)
		(pad "117" smd rect
			(at -2.050034 40.375078 90)
			(size 0.519938 1.4986)
			(layers "F.Cu" "F.Mask" "F.Paste")
			(net "GND")
		)
		(pad "118" smd rect
			(at -2.050034 41.224962 90)
			(size 0.519938 1.4986)
			(layers "F.Cu" "F.Mask" "F.Paste")
			(net "M_F_CPU0_SB_DQ<12>")
		)
		(pad "119" smd rect
			(at -2.050034 42.0751 90)
			(size 0.519938 1.4986)
			(layers "F.Cu" "F.Mask" "F.Paste")
			(net "GND")
		)
		(pad "120" smd rect
			(at -2.050034 42.924984 90)
			(size 0.519938 1.4986)
			(layers "F.Cu" "F.Mask" "F.Paste")
			(net "M_F_CPU0_SB_DQ<13>")
		)
		(pad "121" smd rect
			(at -2.050034 43.775122 90)
			(size 0.519938 1.4986)
			(layers "F.Cu" "F.Mask" "F.Paste")
			(net "GND")
		)
		(pad "122" smd rect
			(at -2.050034 44.625006 90)
			(size 0.519938 1.4986)
			(layers "F.Cu" "F.Mask" "F.Paste")
			(net "M_F_CPU0_SB_DQ<16>")
		)
		(pad "123" smd rect
			(at -2.050034 45.47489 90)
			(size 0.519938 1.4986)
			(layers "F.Cu" "F.Mask" "F.Paste")
			(net "GND")
		)
		(pad "124" smd rect
			(at -2.050034 46.325028 90)
			(size 0.519938 1.4986)
			(layers "F.Cu" "F.Mask" "F.Paste")
			(net "M_F_CPU0_SB_DQ<17>")
		)
		(pad "125" smd rect
			(at -2.050034 47.174912 90)
			(size 0.519938 1.4986)
			(layers "F.Cu" "F.Mask" "F.Paste")
			(net "GND")
		)
		(pad "126" smd rect
			(at -2.050034 48.02505 90)
			(size 0.519938 1.4986)
			(layers "F.Cu" "F.Mask" "F.Paste")
			(net "M_F_CPU0_SB_DQS_DP<2>")
		)
		(pad "127" smd rect
			(at -2.050034 48.874934 90)
			(size 0.519938 1.4986)
			(layers "F.Cu" "F.Mask" "F.Paste")
			(net "M_F_CPU0_SB_DQS_DN<2>")
		)
		(pad "128" smd rect
			(at -2.050034 49.725072 90)
			(size 0.519938 1.4986)
			(layers "F.Cu" "F.Mask" "F.Paste")
			(net "GND")
		)
		(pad "129" smd rect
			(at -2.050034 50.574956 90)
			(size 0.519938 1.4986)
			(layers "F.Cu" "F.Mask" "F.Paste")
			(net "M_F_CPU0_SB_DQ<20>")
		)
		(pad "130" smd rect
			(at -2.050034 51.425094 90)
			(size 0.519938 1.4986)
			(layers "F.Cu" "F.Mask" "F.Paste")
			(net "GND")
		)
		(pad "131" smd rect
			(at -2.050034 52.274978 90)
			(size 0.519938 1.4986)
			(layers "F.Cu" "F.Mask" "F.Paste")
			(net "M_F_CPU0_SB_DQ<21>")
		)
		(pad "132" smd rect
			(at -2.050034 53.125116 90)
			(size 0.519938 1.4986)
			(layers "F.Cu" "F.Mask" "F.Paste")
			(net "GND")
		)
		(pad "133" smd rect
			(at -2.050034 53.975 90)
			(size 0.519938 1.4986)
			(layers "F.Cu" "F.Mask" "F.Paste")
			(net "M_F_CPU0_SB_DQ<24>")
		)
		(pad "134" smd rect
			(at -2.050034 54.824884 90)
			(size 0.519938 1.4986)
			(layers "F.Cu" "F.Mask" "F.Paste")
			(net "GND")
		)
		(pad "135" smd rect
			(at -2.050034 55.675022 90)
			(size 0.519938 1.4986)
			(layers "F.Cu" "F.Mask" "F.Paste")
			(net "M_F_CPU0_SB_DQ<25>")
		)
		(pad "136" smd rect
			(at -2.050034 56.524906 90)
			(size 0.519938 1.4986)
			(layers "F.Cu" "F.Mask" "F.Paste")
			(net "GND")
		)
		(pad "137" smd rect
			(at -2.050034 57.375044 90)
			(size 0.519938 1.4986)
			(layers "F.Cu" "F.Mask" "F.Paste")
			(net "M_F_CPU0_SB_DQS_DP<3>")
		)
		(pad "138" smd rect
			(at -2.050034 58.224928 90)
			(size 0.519938 1.4986)
			(layers "F.Cu" "F.Mask" "F.Paste")
			(net "M_F_CPU0_SB_DQS_DN<3>")
		)
		(pad "139" smd rect
			(at -2.050034 59.075066 90)
			(size 0.519938 1.4986)
			(layers "F.Cu" "F.Mask" "F.Paste")
			(net "GND")
		)
		(pad "140" smd rect
			(at -2.050034 59.92495 90)
			(size 0.519938 1.4986)
			(layers "F.Cu" "F.Mask" "F.Paste")
			(net "M_F_CPU0_SB_DQ<28>")
		)
		(pad "141" smd rect
			(at -2.050034 60.775088 90)
			(size 0.519938 1.4986)
			(layers "F.Cu" "F.Mask" "F.Paste")
			(net "GND")
		)
		(pad "142" smd rect
			(at -2.050034 61.624972 90)
			(size 0.519938 1.4986)
			(layers "F.Cu" "F.Mask" "F.Paste")
			(net "M_F_CPU0_SB_DQ<29>")
		)
		(pad "143" smd rect
			(at -2.050034 62.47511 90)
			(size 0.519938 1.4986)
			(layers "F.Cu" "F.Mask" "F.Paste")
			(net "GND")
		)
		(pad "144" smd rect
			(at -2.050034 63.324994 90)
			(size 0.519938 1.4986)
			(layers "F.Cu" "F.Mask" "F.Paste")
			(net "Net_2320")
		)
		(pad "145" smd rect
			(at 2.050034 -63.324994 90)
			(size 0.519938 1.4986)
			(layers "F.Cu" "F.Mask" "F.Paste")
			(net "P12V_MEM_CPU0")
		)
		(pad "146" smd rect
			(at 2.050034 -62.47511 90)
			(size 0.519938 1.4986)
			(layers "F.Cu" "F.Mask" "F.Paste")
			(net "P12V_MEM_CPU0")
		)
		(pad "147" smd rect
			(at 2.050034 -61.624972 90)
			(size 0.519938 1.4986)
			(layers "F.Cu" "F.Mask" "F.Paste")
			(net "PWRGD_CHF_CPU0_DIMM")
		)
		(pad "148" smd rect
			(at 2.050034 -60.775088 90)
			(size 0.519938 1.4986)
			(layers "F.Cu" "F.Mask" "F.Paste")
			(net "PD_CHF_CPU0_DIMM_SAA")
		)
		(pad "149" smd rect
			(at 2.050034 -59.92495 90)
			(size 0.519938 1.4986)
			(layers "F.Cu" "F.Mask" "F.Paste")
			(net "Net_2321")
		)
		(pad "150" smd rect
			(at 2.050034 -59.075066 90)
			(size 0.519938 1.4986)
			(layers "F.Cu" "F.Mask" "F.Paste")
			(net "Net_2322")
		)
		(pad "151" smd rect
			(at 2.050034 -58.224928 90)
			(size 0.519938 1.4986)
			(layers "F.Cu" "F.Mask" "F.Paste")
			(net "GND")
		)
		(pad "152" smd rect
			(at 2.050034 -57.375044 90)
			(size 0.519938 1.4986)
			(layers "F.Cu" "F.Mask" "F.Paste")
			(net "M_F_CPU0_SA_DQ<2>")
		)
		(pad "153" smd rect
			(at 2.050034 -56.524906 90)
			(size 0.519938 1.4986)
			(layers "F.Cu" "F.Mask" "F.Paste")
			(net "GND")
		)
		(pad "154" smd rect
			(at 2.050034 -55.675022 90)
			(size 0.519938 1.4986)
			(layers "F.Cu" "F.Mask" "F.Paste")
			(net "M_F_CPU0_SA_DQ<3>")
		)
		(pad "155" smd rect
			(at 2.050034 -54.824884 90)
			(size 0.519938 1.4986)
			(layers "F.Cu" "F.Mask" "F.Paste")
			(net "GND")
		)
		(pad "156" smd rect
			(at 2.050034 -53.975 90)
			(size 0.519938 1.4986)
			(layers "F.Cu" "F.Mask" "F.Paste")
			(net "M_F_CPU0_SA_DQS_DN<5>")
		)
		(pad "157" smd rect
			(at 2.050034 -53.125116 90)
			(size 0.519938 1.4986)
			(layers "F.Cu" "F.Mask" "F.Paste")
			(net "M_F_CPU0_SA_DQS_DP<5>")
		)
		(pad "158" smd rect
			(at 2.050034 -52.274978 90)
			(size 0.519938 1.4986)
			(layers "F.Cu" "F.Mask" "F.Paste")
			(net "GND")
		)
		(pad "159" smd rect
			(at 2.050034 -51.425094 90)
			(size 0.519938 1.4986)
			(layers "F.Cu" "F.Mask" "F.Paste")
			(net "M_F_CPU0_SA_DQ<6>")
		)
		(pad "160" smd rect
			(at 2.050034 -50.574956 90)
			(size 0.519938 1.4986)
			(layers "F.Cu" "F.Mask" "F.Paste")
			(net "GND")
		)
		(pad "161" smd rect
			(at 2.050034 -49.725072 90)
			(size 0.519938 1.4986)
			(layers "F.Cu" "F.Mask" "F.Paste")
			(net "M_F_CPU0_SA_DQ<7>")
		)
		(pad "162" smd rect
			(at 2.050034 -48.874934 90)
			(size 0.519938 1.4986)
			(layers "F.Cu" "F.Mask" "F.Paste")
			(net "GND")
		)
		(pad "163" smd rect
			(at 2.050034 -48.02505 90)
			(size 0.519938 1.4986)
			(layers "F.Cu" "F.Mask" "F.Paste")
			(net "M_F_CPU0_SA_DQ<10>")
		)
		(pad "164" smd rect
			(at 2.050034 -47.174912 90)
			(size 0.519938 1.4986)
			(layers "F.Cu" "F.Mask" "F.Paste")
			(net "GND")
		)
		(pad "165" smd rect
			(at 2.050034 -46.325028 90)
			(size 0.519938 1.4986)
			(layers "F.Cu" "F.Mask" "F.Paste")
			(net "M_F_CPU0_SA_DQ<11>")
		)
		(pad "166" smd rect
			(at 2.050034 -45.47489 90)
			(size 0.519938 1.4986)
			(layers "F.Cu" "F.Mask" "F.Paste")
			(net "GND")
		)
		(pad "167" smd rect
			(at 2.050034 -44.625006 90)
			(size 0.519938 1.4986)
			(layers "F.Cu" "F.Mask" "F.Paste")
			(net "M_F_CPU0_SA_DQS_DN<6>")
		)
		(pad "168" smd rect
			(at 2.050034 -43.775122 90)
			(size 0.519938 1.4986)
			(layers "F.Cu" "F.Mask" "F.Paste")
			(net "M_F_CPU0_SA_DQS_DP<6>")
		)
		(pad "169" smd rect
			(at 2.050034 -42.924984 90)
			(size 0.519938 1.4986)
			(layers "F.Cu" "F.Mask" "F.Paste")
			(net "GND")
		)
		(pad "170" smd rect
			(at 2.050034 -42.0751 90)
			(size 0.519938 1.4986)
			(layers "F.Cu" "F.Mask" "F.Paste")
			(net "M_F_CPU0_SA_DQ<14>")
		)
		(pad "171" smd rect
			(at 2.050034 -41.224962 90)
			(size 0.519938 1.4986)
			(layers "F.Cu" "F.Mask" "F.Paste")
			(net "GND")
		)
		(pad "172" smd rect
			(at 2.050034 -40.375078 90)
			(size 0.519938 1.4986)
			(layers "F.Cu" "F.Mask" "F.Paste")
			(net "M_F_CPU0_SA_DQ<15>")
		)
		(pad "173" smd rect
			(at 2.050034 -39.52494 90)
			(size 0.519938 1.4986)
			(layers "F.Cu" "F.Mask" "F.Paste")
			(net "GND")
		)
		(pad "174" smd rect
			(at 2.050034 -38.675056 90)
			(size 0.519938 1.4986)
			(layers "F.Cu" "F.Mask" "F.Paste")
			(net "M_F_CPU0_SA_DQ<18>")
		)
		(pad "175" smd rect
			(at 2.050034 -37.824918 90)
			(size 0.519938 1.4986)
			(layers "F.Cu" "F.Mask" "F.Paste")
			(net "GND")
		)
		(pad "176" smd rect
			(at 2.050034 -36.975034 90)
			(size 0.519938 1.4986)
			(layers "F.Cu" "F.Mask" "F.Paste")
			(net "M_F_CPU0_SA_DQ<19>")
		)
		(pad "177" smd rect
			(at 2.050034 -36.124896 90)
			(size 0.519938 1.4986)
			(layers "F.Cu" "F.Mask" "F.Paste")
			(net "GND")
		)
		(pad "178" smd rect
			(at 2.050034 -35.275012 90)
			(size 0.519938 1.4986)
			(layers "F.Cu" "F.Mask" "F.Paste")
			(net "M_F_CPU0_SA_DQS_DN<7>")
		)
		(pad "179" smd rect
			(at 2.050034 -34.425128 90)
			(size 0.519938 1.4986)
			(layers "F.Cu" "F.Mask" "F.Paste")
			(net "M_F_CPU0_SA_DQS_DP<7>")
		)
		(pad "180" smd rect
			(at 2.050034 -33.57499 90)
			(size 0.519938 1.4986)
			(layers "F.Cu" "F.Mask" "F.Paste")
			(net "GND")
		)
		(pad "181" smd rect
			(at 2.050034 -32.725106 90)
			(size 0.519938 1.4986)
			(layers "F.Cu" "F.Mask" "F.Paste")
			(net "M_F_CPU0_SA_DQ<22>")
		)
		(pad "182" smd rect
			(at 2.050034 -31.874968 90)
			(size 0.519938 1.4986)
			(layers "F.Cu" "F.Mask" "F.Paste")
			(net "GND")
		)
		(pad "183" smd rect
			(at 2.050034 -31.025084 90)
			(size 0.519938 1.4986)
			(layers "F.Cu" "F.Mask" "F.Paste")
			(net "M_F_CPU0_SA_DQ<23>")
		)
		(pad "184" smd rect
			(at 2.050034 -30.174946 90)
			(size 0.519938 1.4986)
			(layers "F.Cu" "F.Mask" "F.Paste")
			(net "GND")
		)
		(pad "185" smd rect
			(at 2.050034 -29.325062 90)
			(size 0.519938 1.4986)
			(layers "F.Cu" "F.Mask" "F.Paste")
			(net "M_F_CPU0_SA_DQ<26>")
		)
		(pad "186" smd rect
			(at 2.050034 -28.474924 90)
			(size 0.519938 1.4986)
			(layers "F.Cu" "F.Mask" "F.Paste")
			(net "GND")
		)
		(pad "187" smd rect
			(at 2.050034 -27.62504 90)
			(size 0.519938 1.4986)
			(layers "F.Cu" "F.Mask" "F.Paste")
			(net "M_F_CPU0_SA_DQ<27>")
		)
		(pad "188" smd rect
			(at 2.050034 -26.774902 90)
			(size 0.519938 1.4986)
			(layers "F.Cu" "F.Mask" "F.Paste")
			(net "GND")
		)
		(pad "189" smd rect
			(at 2.050034 -25.925018 90)
			(size 0.519938 1.4986)
			(layers "F.Cu" "F.Mask" "F.Paste")
			(net "M_F_CPU0_SA_DQS_DN<8>")
		)
		(pad "190" smd rect
			(at 2.050034 -25.07488 90)
			(size 0.519938 1.4986)
			(layers "F.Cu" "F.Mask" "F.Paste")
			(net "M_F_CPU0_SA_DQS_DP<8>")
		)
		(pad "191" smd rect
			(at 2.050034 -24.224996 90)
			(size 0.519938 1.4986)
			(layers "F.Cu" "F.Mask" "F.Paste")
			(net "GND")
		)
		(pad "192" smd rect
			(at 2.050034 -23.375112 90)
			(size 0.519938 1.4986)
			(layers "F.Cu" "F.Mask" "F.Paste")
			(net "M_F_CPU0_SA_DQ<30>")
		)
		(pad "193" smd rect
			(at 2.050034 -22.524974 90)
			(size 0.519938 1.4986)
			(layers "F.Cu" "F.Mask" "F.Paste")
			(net "GND")
		)
		(pad "194" smd rect
			(at 2.050034 -21.67509 90)
			(size 0.519938 1.4986)
			(layers "F.Cu" "F.Mask" "F.Paste")
			(net "M_F_CPU0_SA_DQ<31>")
		)
		(pad "195" smd rect
			(at 2.050034 -20.824952 90)
			(size 0.519938 1.4986)
			(layers "F.Cu" "F.Mask" "F.Paste")
			(net "GND")
		)
		(pad "196" smd rect
			(at 2.050034 -19.975068 90)
			(size 0.519938 1.4986)
			(layers "F.Cu" "F.Mask" "F.Paste")
			(net "M_F_CPU0_SA_CB<2>")
		)
		(pad "197" smd rect
			(at 2.050034 -19.12493 90)
			(size 0.519938 1.4986)
			(layers "F.Cu" "F.Mask" "F.Paste")
			(net "GND")
		)
		(pad "198" smd rect
			(at 2.050034 -18.275046 90)
			(size 0.519938 1.4986)
			(layers "F.Cu" "F.Mask" "F.Paste")
			(net "M_F_CPU0_SA_CB<3>")
		)
		(pad "199" smd rect
			(at 2.050034 -17.424908 90)
			(size 0.519938 1.4986)
			(layers "F.Cu" "F.Mask" "F.Paste")
			(net "GND")
		)
		(pad "200" smd rect
			(at 2.050034 -16.575024 90)
			(size 0.519938 1.4986)
			(layers "F.Cu" "F.Mask" "F.Paste")
			(net "M_F_CPU0_SA_DQS_DN<9>")
		)
		(pad "201" smd rect
			(at 2.050034 -15.724886 90)
			(size 0.519938 1.4986)
			(layers "F.Cu" "F.Mask" "F.Paste")
			(net "M_F_CPU0_SA_DQS_DP<9>")
		)
		(pad "202" smd rect
			(at 2.050034 -14.875002 90)
			(size 0.519938 1.4986)
			(layers "F.Cu" "F.Mask" "F.Paste")
			(net "GND")
		)
		(pad "203" smd rect
			(at 2.050034 -14.025118 90)
			(size 0.519938 1.4986)
			(layers "F.Cu" "F.Mask" "F.Paste")
			(net "M_F_CPU0_SA_CB<6>")
		)
		(pad "204" smd rect
			(at 2.050034 -13.17498 90)
			(size 0.519938 1.4986)
			(layers "F.Cu" "F.Mask" "F.Paste")
			(net "GND")
		)
		(pad "205" smd rect
			(at 2.050034 -12.325096 90)
			(size 0.519938 1.4986)
			(layers "F.Cu" "F.Mask" "F.Paste")
			(net "M_F_CPU0_SA_CB<7>")
		)
		(pad "206" smd rect
			(at 2.050034 -11.474958 90)
			(size 0.519938 1.4986)
			(layers "F.Cu" "F.Mask" "F.Paste")
			(net "GND")
		)
		(pad "207" smd rect
			(at 2.050034 -10.625074 90)
			(size 0.519938 1.4986)
			(layers "F.Cu" "F.Mask" "F.Paste")
			(net "M_F_CPU0_RESET_N")
		)
		(pad "208" smd rect
			(at 2.050034 -9.774936 90)
			(size 0.519938 1.4986)
			(layers "F.Cu" "F.Mask" "F.Paste")
			(net "GND")
		)
		(pad "209" smd rect
			(at 2.050034 -8.925052 90)
			(size 0.519938 1.4986)
			(layers "F.Cu" "F.Mask" "F.Paste")
			(net "M_F_CPU0_SA_CS_N<1>")
		)
		(pad "210" smd rect
			(at 2.050034 -8.074914 90)
			(size 0.519938 1.4986)
			(layers "F.Cu" "F.Mask" "F.Paste")
			(net "GND")
		)
		(pad "211" smd rect
			(at 2.050034 -7.22503 90)
			(size 0.519938 1.4986)
			(layers "F.Cu" "F.Mask" "F.Paste")
			(net "M_F_CPU0_SA_CA<1>")
		)
		(pad "212" smd rect
			(at 2.050034 -6.374892 90)
			(size 0.519938 1.4986)
			(layers "F.Cu" "F.Mask" "F.Paste")
			(net "GND")
		)
		(pad "213" smd rect
			(at 2.050034 -5.525008 90)
			(size 0.519938 1.4986)
			(layers "F.Cu" "F.Mask" "F.Paste")
			(net "M_F_CPU0_SA_CA<3>")
		)
		(pad "214" smd rect
			(at 2.050034 -4.675124 90)
			(size 0.519938 1.4986)
			(layers "F.Cu" "F.Mask" "F.Paste")
			(net "GND")
		)
		(pad "215" smd rect
			(at 2.050034 -3.824986 90)
			(size 0.519938 1.4986)
			(layers "F.Cu" "F.Mask" "F.Paste")
			(net "M_F_CPU0_SA_CA<5>")
		)
		(pad "216" smd rect
			(at 2.050034 -2.975102 90)
			(size 0.519938 1.4986)
			(layers "F.Cu" "F.Mask" "F.Paste")
			(net "GND")
		)
		(pad "217" smd rect
			(at 2.050034 -2.124964 90)
			(size 0.519938 1.4986)
			(layers "F.Cu" "F.Mask" "F.Paste")
			(net "M_F_CPU0_CLK_DP<0>")
		)
		(pad "218" smd rect
			(at 2.050034 -1.27508 90)
			(size 0.519938 1.4986)
			(layers "F.Cu" "F.Mask" "F.Paste")
			(net "M_F_CPU0_CLK_DN<0>")
		)
		(pad "219" smd rect
			(at 2.050034 -0.424942 90)
			(size 0.519938 1.4986)
			(layers "F.Cu" "F.Mask" "F.Paste")
			(net "GND")
		)
		(pad "220" smd rect
			(at 2.050034 5.525008 90)
			(size 0.519938 1.4986)
			(layers "F.Cu" "F.Mask" "F.Paste")
			(net "Net_2323")
		)
		(pad "221" smd rect
			(at 2.050034 6.374892 90)
			(size 0.519938 1.4986)
			(layers "F.Cu" "F.Mask" "F.Paste")
			(net "M_F_CPU0_SB_CA<1>")
		)
		(pad "222" smd rect
			(at 2.050034 7.22503 90)
			(size 0.519938 1.4986)
			(layers "F.Cu" "F.Mask" "F.Paste")
			(net "GND")
		)
		(pad "223" smd rect
			(at 2.050034 8.074914 90)
			(size 0.519938 1.4986)
			(layers "F.Cu" "F.Mask" "F.Paste")
			(net "M_F_CPU0_SB_CA<3>")
		)
		(pad "224" smd rect
			(at 2.050034 8.925052 90)
			(size 0.519938 1.4986)
			(layers "F.Cu" "F.Mask" "F.Paste")
			(net "GND")
		)
		(pad "225" smd rect
			(at 2.050034 9.774936 90)
			(size 0.519938 1.4986)
			(layers "F.Cu" "F.Mask" "F.Paste")
			(net "M_F_CPU0_SB_CA<5>")
		)
		(pad "226" smd rect
			(at 2.050034 10.625074 90)
			(size 0.519938 1.4986)
			(layers "F.Cu" "F.Mask" "F.Paste")
			(net "GND")
		)
	)
)
